# T6G (Grand Teton) — schematic netlist excerpt (pin names and nets, part order shuffled) for the footprints in the layout excerpt that follows; sources: Cadence DE-HDL packaged netlist, KiCad conversion of 04192023_DAF0TMB3IC0_F0TG_MB_C_brd_V02_OCP.brd

R134  Q_RES  4.7K 5% EMPTY  pkg 0402LF  page 83 : A = FM_APML_MUX2_OE_N ; B = P3V3_AUX
R3136  Q_RES  1K 1% CHIP  pkg 0402LF  page 140 : A = P3V3_AUX ; B = OCP_V3_2_PRSNT3_R_N

(kicad_pcb
	(version 20260206)
	(generator "pcbnew")
	(generator_version "10.0")
	(general
		(thickness 1.6)
		(legacy_teardrops no)
	)
	(paper "A4")
	(title_block
		(title "04192023_DAF0TMB3IC0_F0TG_MB_C_brd_V02_OCP.brd")
		(comment 1 "Grand Teton / footprints 3330-3331 of 8354")
	)
	(layers
		(0 "F.Cu" signal "TOP")
		(4 "In1.Cu" signal "GND")
		(6 "In2.Cu" signal "IN1")
		(8 "In3.Cu" signal "GND1")
		(10 "In4.Cu" signal "IN2")
		(12 "In5.Cu" signal "GND2")
		(14 "In6.Cu" signal "IN3")
		(16 "In7.Cu" signal "GND3")
		(18 "In8.Cu" signal "VCC")
		(20 "In9.Cu" signal "VCC1")
		(22 "In10.Cu" signal "GND4")
		(24 "In11.Cu" signal "IN4")
		(26 "In12.Cu" signal "GND5")
		(28 "In13.Cu" signal "IN5")
		(30 "In14.Cu" signal "GND6")
		(32 "In15.Cu" signal "IN6")
		(34 "In16.Cu" signal "GND7")
		(2 "B.Cu" signal "BOTTOM")
		(9 "F.Adhes" user "F.Adhesive")
		(11 "B.Adhes" user "B.Adhesive")
		(13 "F.Paste" user "Package Geometry/Pastemask Top")
		(15 "B.Paste" user "Package Geometry/Pastemask Bottom")
		(5 "F.SilkS" user "Ref Des/Silkscreen Top")
		(7 "B.SilkS" user "Ref Des/Silkscreen Bottom")
		(1 "F.Mask" user "Board Geometry/Soldermask Top")
		(3 "B.Mask" user "Board Geometry/Soldermask Bottom")
		(17 "Dwgs.User" user "User.Drawings")
		(19 "Cmts.User" user "User.Comments")
		(21 "Eco1.User" user "User.Eco1")
		(23 "Eco2.User" user "User.Eco2")
		(25 "Edge.Cuts" user "Board Geometry/Outline")
		(27 "Margin" user)
		(31 "F.CrtYd" user "Package Geometry/Place Bound Top")
		(29 "B.CrtYd" user "Package Geometry/Place Bound Bottom")
		(35 "F.Fab" user "Ref Des/Assembly Top")
		(33 "B.Fab" user "Ref Des/Assembly Bottom")
	)
	(footprint ""
		(layer "F.Cu")
		(at 212.993732 -111.646208 180)
		(property "Reference" "R134"
			(at 0 0 180)
			(layer "F.SilkS")
			(hide yes)
			(effects
				(font
					(size 1.27 1.27)
				)
			)
		)
		(property "Value" ""
			(at 0 0 180)
			(layer "F.Fab")
			(effects
				(font
					(size 1.27 1.27)
				)
			)
		)
		(duplicate_pad_numbers_are_jumpers no)
		(fp_line
			(start 0.7874 0.4064)
			(end -0.7874 0.4064)
			(stroke
				(width 0.1524)
				(type default)
			)
			(layer "F.SilkS")
		)
		(fp_line
			(start 0.7874 -0.4064)
			(end 0.7874 0.4064)
			(stroke
				(width 0.1524)
				(type default)
			)
			(layer "F.SilkS")
		)
		(fp_line
			(start -0.7874 0.4064)
			(end -0.7874 -0.4064)
			(stroke
				(width 0.1524)
				(type default)
			)
			(layer "F.SilkS")
		)
		(fp_line
			(start -0.7874 -0.4064)
			(end 0.7874 -0.4064)
			(stroke
				(width 0.1524)
				(type default)
			)
			(layer "F.SilkS")
		)
		(fp_line
			(start 0.67945 0.3048)
			(end 0.120396 0.3048)
			(stroke
				(width 0.1)
				(type default)
			)
			(layer "F.Fab")
		)
		(fp_line
			(start 0.67945 -0.3048)
			(end 0.67945 0.3048)
			(stroke
				(width 0.1)
				(type default)
			)
			(layer "F.Fab")
		)
		(fp_line
			(start 0.12065 -0.2794)
			(end 0.12065 -0.3048)
			(stroke
				(width 0.1)
				(type default)
			)
			(layer "F.Fab")
		)
		(fp_line
			(start 0.12065 -0.3048)
			(end 0.67945 -0.3048)
			(stroke
				(width 0.1)
				(type default)
			)
			(layer "F.Fab")
		)
		(fp_line
			(start 0.120396 0.3048)
			(end 0.120396 0.2794)
			(stroke
				(width 0.1)
				(type default)
			)
			(layer "F.Fab")
		)
		(fp_line
			(start 0.120396 0.2794)
			(end -0.12065 0.2794)
			(stroke
				(width 0.1)
				(type default)
			)
			(layer "F.Fab")
		)
		(fp_line
			(start -0.12065 0.3048)
			(end -0.67945 0.3048)
			(stroke
				(width 0.1)
				(type default)
			)
			(layer "F.Fab")
		)
		(fp_line
			(start -0.12065 0.2794)
			(end -0.12065 0.3048)
			(stroke
				(width 0.1)
				(type default)
			)
			(layer "F.Fab")
		)
		(fp_line
			(start -0.12065 -0.2794)
			(end 0.12065 -0.2794)
			(stroke
				(width 0.1)
				(type default)
			)
			(layer "F.Fab")
		)
		(fp_line
			(start -0.12065 -0.305054)
			(end -0.12065 -0.2794)
			(stroke
				(width 0.1)
				(type default)
			)
			(layer "F.Fab")
		)
		(fp_line
			(start -0.67945 0.3048)
			(end -0.67945 -0.305054)
			(stroke
				(width 0.1)
				(type default)
			)
			(layer "F.Fab")
		)
		(fp_line
			(start -0.67945 -0.305054)
			(end -0.12065 -0.305054)
			(stroke
				(width 0.1)
				(type default)
			)
			(layer "F.Fab")
		)
		(pad "1" smd circle
			(at -0.40005 0 180)
			(size 0 0)
			(layers "F.Cu" "F.Mask" "F.Paste")
			(net "FM_APML_MUX2_OE_N")
		)
		(pad "2" smd circle
			(at 0.40005 0 180)
			(size 0 0)
			(layers "F.Cu" "F.Mask" "F.Paste")
			(net "P3V3_AUX")
		)
	)
	(footprint ""
		(layer "F.Cu")
		(at 9.74471 -70.560692)
		(property "Reference" "R3136"
			(at 0 0 0)
			(layer "F.SilkS")
			(hide yes)
			(effects
				(font
					(size 1.27 1.27)
				)
			)
		)
		(property "Value" ""
			(at 0 0 0)
			(layer "F.Fab")
			(effects
				(font
					(size 1.27 1.27)
				)
			)
		)
		(duplicate_pad_numbers_are_jumpers no)
		(fp_line
			(start -0.7874 -0.4064)
			(end 0.7874 -0.4064)
			(stroke
				(width 0.1524)
				(type default)
			)
			(layer "F.SilkS")
		)
		(fp_line
			(start -0.7874 0.4064)
			(end -0.7874 -0.4064)
			(stroke
				(width 0.1524)
				(type default)
			)
			(layer "F.SilkS")
		)
		(fp_line
			(start 0.7874 -0.4064)
			(end 0.7874 0.4064)
			(stroke
				(width 0.1524)
				(type default)
			)
			(layer "F.SilkS")
		)
		(fp_line
			(start 0.7874 0.4064)
			(end -0.7874 0.4064)
			(stroke
				(width 0.1524)
				(type default)
			)
			(layer "F.SilkS")
		)
		(fp_line
			(start -0.67945 -0.305054)
			(end -0.12065 -0.305054)
			(stroke
				(width 0.1)
				(type default)
			)
			(layer "F.Fab")
		)
		(fp_line
			(start -0.67945 0.3048)
			(end -0.67945 -0.305054)
			(stroke
				(width 0.1)
				(type default)
			)
			(layer "F.Fab")
		)
		(fp_line
			(start -0.12065 -0.305054)
			(end -0.12065 -0.2794)
			(stroke
				(width 0.1)
				(type default)
			)
			(layer "F.Fab")
		)
		(fp_line
			(start -0.12065 -0.2794)
			(end 0.12065 -0.2794)
			(stroke
				(width 0.1)
				(type default)
			)
			(layer "F.Fab")
		)
		(fp_line
			(start -0.12065 0.2794)
			(end -0.12065 0.3048)
			(stroke
				(width 0.1)
				(type default)
			)
			(layer "F.Fab")
		)
		(fp_line
			(start -0.12065 0.3048)
			(end -0.67945 0.3048)
			(stroke
				(width 0.1)
				(type default)
			)
			(layer "F.Fab")
		)
		(fp_line
			(start 0.120396 0.2794)
			(end -0.12065 0.2794)
			(stroke
				(width 0.1)
				(type default)
			)
			(layer "F.Fab")
		)
		(fp_line
			(start 0.120396 0.3048)
			(end 0.120396 0.2794)
			(stroke
				(width 0.1)
				(type default)
			)
			(layer "F.Fab")
		)
		(fp_line
			(start 0.12065 -0.3048)
			(end 0.67945 -0.3048)
			(stroke
				(width 0.1)
				(type default)
			)
			(layer "F.Fab")
		)
		(fp_line
			(start 0.12065 -0.2794)
			(end 0.12065 -0.3048)
			(stroke
				(width 0.1)
				(type default)
			)
			(layer "F.Fab")
		)
		(fp_line
			(start 0.67945 -0.3048)
			(end 0.67945 0.3048)
			(stroke
				(width 0.1)
				(type default)
			)
			(layer "F.Fab")
		)
		(fp_line
			(start 0.67945 0.3048)
			(end 0.120396 0.3048)
			(stroke
				(width 0.1)
				(type default)
			)
			(layer "F.Fab")
		)
		(pad "1" smd circle
			(at -0.40005 0)
			(size 0 0)
			(layers "F.Cu" "F.Mask" "F.Paste")
			(net "P3V3_AUX")
		)
		(pad "2" smd circle
			(at 0.40005 0)
			(size 0 0)
			(layers "F.Cu" "F.Mask" "F.Paste")
			(net "OCP_V3_2_PRSNT3_R_N")
		)
	)
)
